(kicad_pcb
	(version 20260206)
	(generator "pcbnew")
	(generator_version "10.0")
	(general
		(thickness 1.6)
		(legacy_teardrops no)
	)
	(paper "A4")
	(title_block
		(title "v1-chassis-manager — T6M_CM_d_v01_1031_1645.brd")
		(comment 1 "Open CloudServer (Microsoft) / footprint 550 of 2512 (U14), pads 236-353 of 408")
	)
	(layers
		(0 "F.Cu" signal "TOP")
		(4 "In1.Cu" signal "GND1")
		(6 "In2.Cu" signal "IN1")
		(8 "In3.Cu" signal "VCC1")
		(10 "In4.Cu" signal "VCC2")
		(12 "In5.Cu" signal "GND2")
		(14 "In6.Cu" signal "IN2")
		(16 "In7.Cu" signal "IN3")
		(18 "In8.Cu" signal "GND3")
		(2 "B.Cu" signal "BOTTOM")
		(9 "F.Adhes" user "F.Adhesive")
		(11 "B.Adhes" user "B.Adhesive")
		(13 "F.Paste" user "Package Geometry/Pastemask Top")
		(15 "B.Paste" user "Package Geometry/Pastemask Bottom")
		(5 "F.SilkS" user "Ref Des/Silkscreen Top")
		(7 "B.SilkS" user "Ref Des/Silkscreen Bottom")
		(1 "F.Mask" user "Board Geometry/Soldermask Top")
		(3 "B.Mask" user "Board Geometry/Soldermask Bottom")
		(17 "Dwgs.User" user "User.Drawings")
		(19 "Cmts.User" user "User.Comments")
		(21 "Eco1.User" user "User.Eco1")
		(23 "Eco2.User" user "User.Eco2")
		(25 "Edge.Cuts" user "Board Geometry/Outline")
		(27 "Margin" user)
		(31 "F.CrtYd" user "Package Geometry/Place Bound Top")
		(29 "B.CrtYd" user "Package Geometry/Place Bound Bottom")
		(35 "F.Fab" user "Ref Des/Assembly Top")
		(33 "B.Fab" user "Ref Des/Assembly Bottom")
	)
	(footprint ""
		(layer "F.Cu")
		(at 65.741804 -134.859522 -90)
		(property "Reference" "U14"
			(at 12.258294 13.71092 90)
			(unlocked yes)
			(layer "F.SilkS")
			(effects
				(font
					(size 1.6002 1.1938)
					(thickness 0.1524)
				)
				(justify left)
			)
		)
		(property "Value" ""
			(at 0 0 270)
			(layer "F.Fab")
			(effects
				(font
					(size 1.27 1.27)
				)
			)
		)
		(duplicate_pad_numbers_are_jumpers no)
		(pad "L6" smd circle
			(at -4.400042 -0.40005 270)
			(size 0.3683 0.3683)
			(layers "F.Cu" "F.Mask" "F.Paste")
			(net "P1V26_BMC_NODE1")
		)
		(pad "L9" smd circle
			(at -1.999996 -0.40005 270)
			(size 0.3683 0.3683)
			(layers "F.Cu" "F.Mask" "F.Paste")
			(net "GND")
		)
		(pad "L10" smd circle
			(at -1.199896 -0.40005 270)
			(size 0.3683 0.3683)
			(layers "F.Cu" "F.Mask" "F.Paste")
			(net "GND")
		)
		(pad "L11" smd circle
			(at -0.40005 -0.40005 270)
			(size 0.3683 0.3683)
			(layers "F.Cu" "F.Mask" "F.Paste")
			(net "GND")
		)
		(pad "L12" smd circle
			(at 0.40005 -0.40005 270)
			(size 0.3683 0.3683)
			(layers "F.Cu" "F.Mask" "F.Paste")
			(net "GND")
		)
		(pad "L13" smd circle
			(at 1.199896 -0.40005 270)
			(size 0.3683 0.3683)
			(layers "F.Cu" "F.Mask" "F.Paste")
			(net "GND")
		)
		(pad "L14" smd circle
			(at 1.999996 -0.40005 270)
			(size 0.3683 0.3683)
			(layers "F.Cu" "F.Mask" "F.Paste")
			(net "GND")
		)
		(pad "L17" smd circle
			(at 4.400042 -0.40005 270)
			(size 0.3683 0.3683)
			(layers "F.Cu" "F.Mask" "F.Paste")
			(net "P1V26_BMC_NODE1")
		)
		(pad "L18" smd circle
			(at 5.199888 -0.40005 270)
			(size 0.3683 0.3683)
			(layers "F.Cu" "F.Mask" "F.Paste")
			(net "BMC_ROMA12")
		)
		(pad "L19" smd circle
			(at 5.999988 -0.40005 270)
			(size 0.3683 0.3683)
			(layers "F.Cu" "F.Mask" "F.Paste")
			(net "BMC_ROMA13")
		)
		(pad "L20" smd circle
			(at 6.800088 -0.40005 270)
			(size 0.3683 0.3683)
			(layers "F.Cu" "F.Mask" "F.Paste")
			(net "BMC_ROMA14")
		)
		(pad "L21" smd circle
			(at 7.599934 -0.40005 270)
			(size 0.3683 0.3683)
			(layers "F.Cu" "F.Mask" "F.Paste")
			(net "BMC_ROMA15")
		)
		(pad "L22" smd circle
			(at 8.400034 -0.40005 270)
			(size 0.3683 0.3683)
			(layers "F.Cu" "F.Mask" "F.Paste")
			(net "BMC_ROMA22")
		)
		(pad "M1" smd circle
			(at -8.400034 0.40005 270)
			(size 0.3683 0.3683)
			(layers "F.Cu" "F.Mask" "F.Paste")
			(net "GND")
		)
		(pad "M2" smd circle
			(at -7.599934 0.40005 270)
			(size 0.3683 0.3683)
			(layers "F.Cu" "F.Mask" "F.Paste")
			(net "GND")
		)
		(pad "M3" smd circle
			(at -6.800088 0.40005 270)
			(size 0.3683 0.3683)
			(layers "F.Cu" "F.Mask" "F.Paste")
			(net "GND")
		)
		(pad "M4" smd circle
			(at -5.999988 0.40005 270)
			(size 0.3683 0.3683)
			(layers "F.Cu" "F.Mask" "F.Paste")
			(net "GND")
		)
		(pad "M5" smd circle
			(at -5.199888 0.40005 270)
			(size 0.3683 0.3683)
			(layers "F.Cu" "F.Mask" "F.Paste")
			(net "GND")
		)
		(pad "M6" smd circle
			(at -4.400042 0.40005 270)
			(size 0.3683 0.3683)
			(layers "F.Cu" "F.Mask" "F.Paste")
			(net "P3V3_NODE1")
		)
		(pad "M9" smd circle
			(at -1.999996 0.40005 270)
			(size 0.3683 0.3683)
			(layers "F.Cu" "F.Mask" "F.Paste")
			(net "GND")
		)
		(pad "M10" smd circle
			(at -1.199896 0.40005 270)
			(size 0.3683 0.3683)
			(layers "F.Cu" "F.Mask" "F.Paste")
			(net "GND")
		)
		(pad "M11" smd circle
			(at -0.40005 0.40005 270)
			(size 0.3683 0.3683)
			(layers "F.Cu" "F.Mask" "F.Paste")
			(net "GND")
		)
		(pad "M12" smd circle
			(at 0.40005 0.40005 270)
			(size 0.3683 0.3683)
			(layers "F.Cu" "F.Mask" "F.Paste")
			(net "GND")
		)
		(pad "M13" smd circle
			(at 1.199896 0.40005 270)
			(size 0.3683 0.3683)
			(layers "F.Cu" "F.Mask" "F.Paste")
			(net "GND")
		)
		(pad "M14" smd circle
			(at 1.999996 0.40005 270)
			(size 0.3683 0.3683)
			(layers "F.Cu" "F.Mask" "F.Paste")
			(net "GND")
		)
		(pad "M17" smd circle
			(at 4.400042 0.40005 270)
			(size 0.3683 0.3683)
			(layers "F.Cu" "F.Mask" "F.Paste")
			(net "P3V3_NODE1")
		)
		(pad "M18" smd circle
			(at 5.199888 0.40005 270)
			(size 0.3683 0.3683)
			(layers "F.Cu" "F.Mask" "F.Paste")
			(net "BMC_ROMA19")
		)
		(pad "M19" smd circle
			(at 5.999988 0.40005 270)
			(size 0.3683 0.3683)
			(layers "F.Cu" "F.Mask" "F.Paste")
			(net "BMC_ROMA8")
		)
		(pad "M20" smd circle
			(at 6.800088 0.40005 270)
			(size 0.3683 0.3683)
			(layers "F.Cu" "F.Mask" "F.Paste")
			(net "BMC_ROMA9")
		)
		(pad "M21" smd circle
			(at 7.599934 0.40005 270)
			(size 0.3683 0.3683)
			(layers "F.Cu" "F.Mask" "F.Paste")
			(net "BMC_ROMA10")
		)
		(pad "M22" smd circle
			(at 8.400034 0.40005 270)
			(size 0.3683 0.3683)
			(layers "F.Cu" "F.Mask" "F.Paste")
			(net "BMC_ROMA11")
		)
		(pad "N1" smd circle
			(at -8.400034 1.199896 270)
			(size 0.3683 0.3683)
			(layers "F.Cu" "F.Mask" "F.Paste")
			(net "GND")
		)
		(pad "N2" smd circle
			(at -7.599934 1.199896 270)
			(size 0.3683 0.3683)
			(layers "F.Cu" "F.Mask" "F.Paste")
			(net "GND")
		)
		(pad "N3" smd circle
			(at -6.800088 1.199896 270)
			(size 0.3683 0.3683)
			(layers "F.Cu" "F.Mask" "F.Paste")
			(net "GND")
		)
		(pad "N4" smd circle
			(at -5.999988 1.199896 270)
			(size 0.3683 0.3683)
			(layers "F.Cu" "F.Mask" "F.Paste")
			(net "GND")
		)
		(pad "N5" smd circle
			(at -5.199888 1.199896 270)
			(size 0.3683 0.3683)
			(layers "F.Cu" "F.Mask" "F.Paste")
			(net "GND")
		)
		(pad "N6" smd circle
			(at -4.400042 1.199896 270)
			(size 0.3683 0.3683)
			(layers "F.Cu" "F.Mask" "F.Paste")
			(net "P3V3_NODE1")
		)
		(pad "N9" smd circle
			(at -1.999996 1.199896 270)
			(size 0.3683 0.3683)
			(layers "F.Cu" "F.Mask" "F.Paste")
			(net "GND")
		)
		(pad "N10" smd circle
			(at -1.199896 1.199896 270)
			(size 0.3683 0.3683)
			(layers "F.Cu" "F.Mask" "F.Paste")
			(net "GND")
		)
		(pad "N11" smd circle
			(at -0.40005 1.199896 270)
			(size 0.3683 0.3683)
			(layers "F.Cu" "F.Mask" "F.Paste")
			(net "GND")
		)
		(pad "N12" smd circle
			(at 0.40005 1.199896 270)
			(size 0.3683 0.3683)
			(layers "F.Cu" "F.Mask" "F.Paste")
			(net "GND")
		)
		(pad "N13" smd circle
			(at 1.199896 1.199896 270)
			(size 0.3683 0.3683)
			(layers "F.Cu" "F.Mask" "F.Paste")
			(net "GND")
		)
		(pad "N14" smd circle
			(at 1.999996 1.199896 270)
			(size 0.3683 0.3683)
			(layers "F.Cu" "F.Mask" "F.Paste")
			(net "GND")
		)
		(pad "N17" smd circle
			(at 4.400042 1.199896 270)
			(size 0.3683 0.3683)
			(layers "F.Cu" "F.Mask" "F.Paste")
			(net "P3V3_NODE1")
		)
		(pad "N18" smd circle
			(at 5.199888 1.199896 270)
			(size 0.3683 0.3683)
			(layers "F.Cu" "F.Mask" "F.Paste")
			(net "BMC_ROMA17")
		)
		(pad "N19" smd circle
			(at 5.999988 1.199896 270)
			(size 0.3683 0.3683)
			(layers "F.Cu" "F.Mask" "F.Paste")
			(net "BMC_ROMA18")
		)
		(pad "N20" smd circle
			(at 6.800088 1.199896 270)
			(size 0.3683 0.3683)
			(layers "F.Cu" "F.Mask" "F.Paste")
			(net "BMC_ROMA21")
		)
		(pad "N21" smd circle
			(at 7.599934 1.199896 270)
			(size 0.3683 0.3683)
			(layers "F.Cu" "F.Mask" "F.Paste")
			(net "Net_515")
		)
		(pad "N22" smd circle
			(at 8.400034 1.199896 270)
			(size 0.3683 0.3683)
			(layers "F.Cu" "F.Mask" "F.Paste")
			(net "BMC_ROMA20")
		)
		(pad "P1" smd circle
			(at -8.400034 1.999996 270)
			(size 0.3683 0.3683)
			(layers "F.Cu" "F.Mask" "F.Paste")
			(net "BMC_NODE1_DACAV33")
		)
		(pad "P2" smd circle
			(at -7.599934 1.999996 270)
			(size 0.3683 0.3683)
			(layers "F.Cu" "F.Mask" "F.Paste")
			(net "BMC_NODE1_ADCREXT")
		)
		(pad "P3" smd circle
			(at -6.800088 1.999996 270)
			(size 0.3683 0.3683)
			(layers "F.Cu" "F.Mask" "F.Paste")
			(net "BMC_NODE1_ADCAV33")
		)
		(pad "P4" smd circle
			(at -5.999988 1.999996 270)
			(size 0.3683 0.3683)
			(layers "F.Cu" "F.Mask" "F.Paste")
			(net "GND")
		)
		(pad "P5" smd circle
			(at -5.199888 1.999996 270)
			(size 0.3683 0.3683)
			(layers "F.Cu" "F.Mask" "F.Paste")
			(net "GND")
		)
		(pad "P6" smd circle
			(at -4.400042 1.999996 270)
			(size 0.3683 0.3683)
			(layers "F.Cu" "F.Mask" "F.Paste")
			(net "P1V26_BMC_NODE1")
		)
		(pad "P9" smd circle
			(at -1.999996 1.999996 270)
			(size 0.3683 0.3683)
			(layers "F.Cu" "F.Mask" "F.Paste")
			(net "GND")
		)
		(pad "P10" smd circle
			(at -1.199896 1.999996 270)
			(size 0.3683 0.3683)
			(layers "F.Cu" "F.Mask" "F.Paste")
			(net "GND")
		)
		(pad "P11" smd circle
			(at -0.40005 1.999996 270)
			(size 0.3683 0.3683)
			(layers "F.Cu" "F.Mask" "F.Paste")
			(net "GND")
		)
		(pad "P12" smd circle
			(at 0.40005 1.999996 270)
			(size 0.3683 0.3683)
			(layers "F.Cu" "F.Mask" "F.Paste")
			(net "GND")
		)
		(pad "P13" smd circle
			(at 1.199896 1.999996 270)
			(size 0.3683 0.3683)
			(layers "F.Cu" "F.Mask" "F.Paste")
			(net "GND")
		)
		(pad "P14" smd circle
			(at 1.999996 1.999996 270)
			(size 0.3683 0.3683)
			(layers "F.Cu" "F.Mask" "F.Paste")
			(net "GND")
		)
		(pad "P17" smd circle
			(at 4.400042 1.999996 270)
			(size 0.3683 0.3683)
			(layers "F.Cu" "F.Mask" "F.Paste")
			(net "P1V26_BMC_NODE1")
		)
		(pad "P18" smd circle
			(at 5.199888 1.999996 270)
			(size 0.3683 0.3683)
			(layers "F.Cu" "F.Mask" "F.Paste")
			(net "BMC_ROMA3")
		)
		(pad "P19" smd circle
			(at 5.999988 1.999996 270)
			(size 0.3683 0.3683)
			(layers "F.Cu" "F.Mask" "F.Paste")
			(net "BMC_ROMA4")
		)
		(pad "P20" smd circle
			(at 6.800088 1.999996 270)
			(size 0.3683 0.3683)
			(layers "F.Cu" "F.Mask" "F.Paste")
			(net "BMC_ROMA5")
		)
		(pad "P21" smd circle
			(at 7.599934 1.999996 270)
			(size 0.3683 0.3683)
			(layers "F.Cu" "F.Mask" "F.Paste")
			(net "BMC_ROMA6")
		)
		(pad "P22" smd circle
			(at 8.400034 1.999996 270)
			(size 0.3683 0.3683)
			(layers "F.Cu" "F.Mask" "F.Paste")
			(net "BMC_ROMA7")
		)
		(pad "R1" smd circle
			(at -8.400034 2.800096 270)
			(size 0.3683 0.3683)
			(layers "F.Cu" "F.Mask" "F.Paste")
			(net "BMC_NODE1_DACRSET")
		)
		(pad "R2" smd circle
			(at -7.599934 2.800096 270)
			(size 0.3683 0.3683)
			(layers "F.Cu" "F.Mask" "F.Paste")
			(net "BMC_NODE1_GFX_RED")
		)
		(pad "R3" smd circle
			(at -6.800088 2.800096 270)
			(size 0.3683 0.3683)
			(layers "F.Cu" "F.Mask" "F.Paste")
			(net "BMC_NODE1_GFX_GREEN")
		)
		(pad "R4" smd circle
			(at -5.999988 2.800096 270)
			(size 0.3683 0.3683)
			(layers "F.Cu" "F.Mask" "F.Paste")
			(net "BMC_NODE1_GFX_BLUE")
		)
		(pad "R5" smd circle
			(at -5.199888 2.800096 270)
			(size 0.3683 0.3683)
			(layers "F.Cu" "F.Mask" "F.Paste")
			(net "GND")
		)
		(pad "R6" smd circle
			(at -4.400042 2.800096 270)
			(size 0.3683 0.3683)
			(layers "F.Cu" "F.Mask" "F.Paste")
			(net "P1V26_BMC_NODE1")
		)
		(pad "R17" smd circle
			(at 4.400042 2.800096 270)
			(size 0.3683 0.3683)
			(layers "F.Cu" "F.Mask" "F.Paste")
			(net "P1V26_BMC_NODE1")
		)
		(pad "R18" smd circle
			(at 5.199888 2.800096 270)
			(size 0.3683 0.3683)
			(layers "F.Cu" "F.Mask" "F.Paste")
			(net "Net_516")
		)
		(pad "R19" smd circle
			(at 5.999988 2.800096 270)
			(size 0.3683 0.3683)
			(layers "F.Cu" "F.Mask" "F.Paste")
			(net "Net_472")
		)
		(pad "R20" smd circle
			(at 6.800088 2.800096 270)
			(size 0.3683 0.3683)
			(layers "F.Cu" "F.Mask" "F.Paste")
			(net "BMC_ROMA0")
		)
		(pad "R21" smd circle
			(at 7.599934 2.800096 270)
			(size 0.3683 0.3683)
			(layers "F.Cu" "F.Mask" "F.Paste")
			(net "BMC_ROMA1")
		)
		(pad "R22" smd circle
			(at 8.400034 2.800096 270)
			(size 0.3683 0.3683)
			(layers "F.Cu" "F.Mask" "F.Paste")
			(net "BMC_ROMA2")
		)
		(pad "T1" smd circle
			(at -8.400034 3.599942 270)
			(size 0.3683 0.3683)
			(layers "F.Cu" "F.Mask" "F.Paste")
			(net "SMB_BMC_NODE1_DDC_DAT")
		)
		(pad "T2" smd circle
			(at -7.599934 3.599942 270)
			(size 0.3683 0.3683)
			(layers "F.Cu" "F.Mask" "F.Paste")
			(net "SMB_BMC_NODE1_DDC_CLK")
		)
		(pad "T3" smd circle
			(at -6.800088 3.599942 270)
			(size 0.3683 0.3683)
			(layers "F.Cu" "F.Mask" "F.Paste")
			(net "BMC_NODE1_DACAV33")
		)
		(pad "T4" smd circle
			(at -5.999988 3.599942 270)
			(size 0.3683 0.3683)
			(layers "F.Cu" "F.Mask" "F.Paste")
			(net "BMC_NODE1_GFX_HSYNC_R")
		)
		(pad "T5" smd circle
			(at -5.199888 3.599942 270)
			(size 0.3683 0.3683)
			(layers "F.Cu" "F.Mask" "F.Paste")
			(net "Net_473")
		)
		(pad "T18" smd circle
			(at 5.199888 3.599942 270)
			(size 0.3683 0.3683)
			(layers "F.Cu" "F.Mask" "F.Paste")
			(net "BMC_ROMA16")
		)
		(pad "T19" smd circle
			(at 5.999988 3.599942 270)
			(size 0.3683 0.3683)
			(layers "F.Cu" "F.Mask" "F.Paste")
			(net "Net_519")
		)
		(pad "T20" smd circle
			(at 6.800088 3.599942 270)
			(size 0.3683 0.3683)
			(layers "F.Cu" "F.Mask" "F.Paste")
			(net "BMC_ROMD2")
		)
		(pad "T21" smd circle
			(at 7.599934 3.599942 270)
			(size 0.3683 0.3683)
			(layers "F.Cu" "F.Mask" "F.Paste")
			(net "BMC_ROMD1")
		)
		(pad "T22" smd circle
			(at 8.400034 3.599942 270)
			(size 0.3683 0.3683)
			(layers "F.Cu" "F.Mask" "F.Paste")
			(net "BMC_ROMD0")
		)
		(pad "U1" smd circle
			(at -8.400034 4.400042 270)
			(size 0.3683 0.3683)
			(layers "F.Cu" "F.Mask" "F.Paste")
			(net "Net_475")
		)
		(pad "U2" smd circle
			(at -7.599934 4.400042 270)
			(size 0.3683 0.3683)
			(layers "F.Cu" "F.Mask" "F.Paste")
			(net "BMC_NODE1_GFX_VSYNC_R")
		)
		(pad "U3" smd circle
			(at -6.800088 4.400042 270)
			(size 0.3683 0.3683)
			(layers "F.Cu" "F.Mask" "F.Paste")
			(net "Net_479")
		)
		(pad "U4" smd circle
			(at -5.999988 4.400042 270)
			(size 0.3683 0.3683)
			(layers "F.Cu" "F.Mask" "F.Paste")
			(net "Net_477")
		)
		(pad "U5" smd circle
			(at -5.199888 4.400042 270)
			(size 0.3683 0.3683)
			(layers "F.Cu" "F.Mask" "F.Paste")
			(net "Net_471")
		)
		(pad "U8" smd circle
			(at -2.800096 4.400042 270)
			(size 0.3683 0.3683)
			(layers "F.Cu" "F.Mask" "F.Paste")
			(net "P3V3_NODE1")
		)
		(pad "U9" smd circle
			(at -1.999996 4.400042 270)
			(size 0.3683 0.3683)
			(layers "F.Cu" "F.Mask" "F.Paste")
			(net "P3V3_NODE1")
		)
		(pad "U10" smd circle
			(at -1.199896 4.400042 270)
			(size 0.3683 0.3683)
			(layers "F.Cu" "F.Mask" "F.Paste")
			(net "P1V538_BMC_NODE1")
		)
		(pad "U11" smd circle
			(at -0.40005 4.400042 270)
			(size 0.3683 0.3683)
			(layers "F.Cu" "F.Mask" "F.Paste")
			(net "P1V538_BMC_NODE1")
		)
		(pad "U12" smd circle
			(at 0.40005 4.400042 270)
			(size 0.3683 0.3683)
			(layers "F.Cu" "F.Mask" "F.Paste")
			(net "P1V26_BMC_NODE1")
		)
		(pad "U13" smd circle
			(at 1.199896 4.400042 270)
			(size 0.3683 0.3683)
			(layers "F.Cu" "F.Mask" "F.Paste")
			(net "P1V26_BMC_NODE1")
		)
		(pad "U14" smd circle
			(at 1.999996 4.400042 270)
			(size 0.3683 0.3683)
			(layers "F.Cu" "F.Mask" "F.Paste")
			(net "P1V538_BMC_NODE1")
		)
		(pad "U15" smd circle
			(at 2.800096 4.400042 270)
			(size 0.3683 0.3683)
			(layers "F.Cu" "F.Mask" "F.Paste")
			(net "P1V538_BMC_NODE1")
		)
		(pad "U18" smd circle
			(at 5.199888 4.400042 270)
			(size 0.3683 0.3683)
			(layers "F.Cu" "F.Mask" "F.Paste")
			(net "Net_1771")
		)
		(pad "U19" smd circle
			(at 5.999988 4.400042 270)
			(size 0.3683 0.3683)
			(layers "F.Cu" "F.Mask" "F.Paste")
			(net "Net_524")
		)
		(pad "U20" smd circle
			(at 6.800088 4.400042 270)
			(size 0.3683 0.3683)
			(layers "F.Cu" "F.Mask" "F.Paste")
			(net "Net_517")
		)
		(pad "U21" smd circle
			(at 7.599934 4.400042 270)
			(size 0.3683 0.3683)
			(layers "F.Cu" "F.Mask" "F.Paste")
			(net "BMC_ROMD4")
		)
		(pad "U22" smd circle
			(at 8.400034 4.400042 270)
			(size 0.3683 0.3683)
			(layers "F.Cu" "F.Mask" "F.Paste")
			(net "BMC_ROMD3")
		)
		(pad "V1" smd circle
			(at -8.400034 5.199888 270)
			(size 0.3683 0.3683)
			(layers "F.Cu" "F.Mask" "F.Paste")
			(net "Net_478")
		)
		(pad "V2" smd circle
			(at -7.599934 5.199888 270)
			(size 0.3683 0.3683)
			(layers "F.Cu" "F.Mask" "F.Paste")
			(net "Net_480")
		)
		(pad "V3" smd circle
			(at -6.800088 5.199888 270)
			(size 0.3683 0.3683)
			(layers "F.Cu" "F.Mask" "F.Paste")
			(net "Net_468")
		)
		(pad "V4" smd circle
			(at -5.999988 5.199888 270)
			(size 0.3683 0.3683)
			(layers "F.Cu" "F.Mask" "F.Paste")
			(net "Net_483")
		)
		(pad "V5" smd circle
			(at -5.199888 5.199888 270)
			(size 0.3683 0.3683)
			(layers "F.Cu" "F.Mask" "F.Paste")
			(net "Net_1751")
		)
		(pad "V6" smd circle
			(at -4.400042 5.199888 270)
			(size 0.3683 0.3683)
			(layers "F.Cu" "F.Mask" "F.Paste")
			(net "Net_509")
		)
		(pad "V7" smd circle
			(at -3.599942 5.199888 270)
			(size 0.3683 0.3683)
			(layers "F.Cu" "F.Mask" "F.Paste")
			(net "Net_1781")
		)
		(pad "V8" smd circle
			(at -2.800096 5.199888 270)
			(size 0.3683 0.3683)
			(layers "F.Cu" "F.Mask" "F.Paste")
			(net "BMC_NODE1_DDR_DM1")
		)
		(pad "V9" smd circle
			(at -1.999996 5.199888 270)
			(size 0.3683 0.3683)
			(layers "F.Cu" "F.Mask" "F.Paste")
			(net "BMC_NODE1_DDR_D13")
		)
		(pad "V10" smd circle
			(at -1.199896 5.199888 270)
			(size 0.3683 0.3683)
			(layers "F.Cu" "F.Mask" "F.Paste")
			(net "BMC_NODE1_DDR_D8")
		)
		(pad "V11" smd circle
			(at -0.40005 5.199888 270)
			(size 0.3683 0.3683)
			(layers "F.Cu" "F.Mask" "F.Paste")
			(net "BMC_NODE1_DDR_D6")
		)
	)
)
